(kicad_pcb
	(version 20260206)
	(generator "pcbnew")
	(generator_version "10.0")
	(general
		(thickness 1.6)
		(legacy_teardrops no)
	)
	(paper "A4")
	(title_block
		(title "Bryce Canyon_F.DPB_16315-1-OCP.brd")
		(comment 1 "Bryce Canyon / footprints 1995-2001 of 2223")
	)
	(layers
		(0 "F.Cu" signal "TOP")
		(4 "In1.Cu" signal "L2GND")
		(6 "In2.Cu" signal "L3")
		(8 "In3.Cu" signal "L4GND")
		(10 "In4.Cu" signal "L5")
		(12 "In5.Cu" signal "L6VCC")
		(14 "In6.Cu" signal "L7VCC")
		(16 "In7.Cu" signal "L8")
		(18 "In8.Cu" signal "L9GND")
		(20 "In9.Cu" signal "L10")
		(22 "In10.Cu" signal "L11GND")
		(2 "B.Cu" signal "BOTTOM")
		(9 "F.Adhes" user "F.Adhesive")
		(11 "B.Adhes" user "B.Adhesive")
		(13 "F.Paste" user "Package Geometry/Pastemask Top")
		(15 "B.Paste" user "Package Geometry/Pastemask Bottom")
		(5 "F.SilkS" user "Ref Des/Silkscreen Top")
		(7 "B.SilkS" user "Ref Des/Silkscreen Bottom")
		(1 "F.Mask" user "Board Geometry/Soldermask Top")
		(3 "B.Mask" user "Board Geometry/Soldermask Bottom")
		(17 "Dwgs.User" user "User.Drawings")
		(19 "Cmts.User" user "User.Comments")
		(21 "Eco1.User" user "User.Eco1")
		(23 "Eco2.User" user "User.Eco2")
		(25 "Edge.Cuts" user "Board Geometry/Outline")
		(27 "Margin" user)
		(31 "F.CrtYd" user "Package Geometry/Place Bound Top")
		(29 "B.CrtYd" user "Package Geometry/Place Bound Bottom")
		(35 "F.Fab" user "Ref Des/Assembly Top")
		(33 "B.Fab" user "Ref Des/Assembly Bottom")
	)
	(footprint ""
		(layer "F.Cu")
		(at 318.600074 -242.745514 180)
		(property "Reference" "Q233"
			(at 0 0 180)
			(layer "F.SilkS")
			(hide yes)
			(effects
				(font
					(size 1.27 1.27)
				)
			)
		)
		(property "Value" "2N7002K-2-GP"
			(at 0.127 -8.9662 180)
			(unlocked yes)
			(layer "F.Fab")
			(hide yes)
			(effects
				(font
					(size 1.016 1.016)
					(thickness 0.1524)
				)
			)
		)
		(property "Device Type" "SOT23DGS2D4H44"
			(at 0.127 -10.4902 180)
			(unlocked yes)
			(layer "F.Fab")
			(hide yes)
			(effects
				(font
					(size 1.016 1.016)
					(thickness 0.1524)
				)
			)
		)
		(duplicate_pad_numbers_are_jumpers no)
		(fp_line
			(start 1.651 1.778)
			(end 1.651 -1.778)
			(stroke
				(width 0.1524)
				(type default)
			)
			(layer "F.SilkS")
		)
		(fp_line
			(start 1.651 -1.778)
			(end -1.651 -1.778)
			(stroke
				(width 0.1524)
				(type default)
			)
			(layer "F.SilkS")
		)
		(fp_line
			(start -1.651 1.778)
			(end 1.651 1.778)
			(stroke
				(width 0.1524)
				(type default)
			)
			(layer "F.SilkS")
		)
		(fp_line
			(start -1.651 -1.778)
			(end -1.651 1.778)
			(stroke
				(width 0.1524)
				(type default)
			)
			(layer "F.SilkS")
		)
		(fp_poly
			(pts
				(xy -1.778 1.8796) (xy -1.778 -1.8796) (xy 1.778 -1.8796) (xy 1.778 1.8796)
			)
			(stroke
				(width 0)
				(type default)
			)
			(fill no)
			(layer "F.CrtYd")
		)
		(fp_poly
			(pts
				(xy -1.778 1.8796) (xy -1.778 -1.8796) (xy 1.778 -1.8796) (xy 1.778 1.8796)
			)
			(stroke
				(width 0)
				(type default)
			)
			(fill no)
			(layer "F.Fab")
		)
		(pad "D" smd custom
			(at 0 -0.9525 180)
			(size 0.1905 0.1905)
			(layers "F.Cu" "F.Mask" "F.Paste")
			(net "FLT_HDD6_N")
			(options
				(clearance outline)
				(anchor circle)
			)
			(primitives
				(gr_poly
					(pts
						(arc
							(start -0.1778 0.5715)
							(mid -0.321484 0.511984)
							(end -0.381 0.3683)
						)
						(arc
							(start -0.381 -0.3683)
							(mid -0.321484 -0.511984)
							(end -0.1778 -0.5715)
						)
						(arc
							(start 0.1778 -0.5715)
							(mid 0.321484 -0.511984)
							(end 0.381 -0.3683)
						)
						(arc
							(start 0.381 0.3683)
							(mid 0.321484 0.511984)
							(end 0.1778 0.5715)
						)
					)
					(width 0)
					(fill yes)
				)
			)
		)
		(pad "G" smd custom
			(at -0.98425 0.9525 180)
			(size 0.1905 0.1905)
			(layers "F.Cu" "F.Mask" "F.Paste")
			(net "DRIVE_A_6_FLT_LED")
			(options
				(clearance outline)
				(anchor circle)
			)
			(primitives
				(gr_poly
					(pts
						(arc
							(start -0.1778 0.5715)
							(mid -0.321484 0.511984)
							(end -0.381 0.3683)
						)
						(arc
							(start -0.381 -0.3683)
							(mid -0.321484 -0.511984)
							(end -0.1778 -0.5715)
						)
						(arc
							(start 0.1778 -0.5715)
							(mid 0.321484 -0.511984)
							(end 0.381 -0.3683)
						)
						(arc
							(start 0.381 0.3683)
							(mid 0.321484 0.511984)
							(end 0.1778 0.5715)
						)
					)
					(width 0)
					(fill yes)
				)
			)
		)
		(pad "S" smd custom
			(at 0.98425 0.9525 180)
			(size 0.1905 0.1905)
			(layers "F.Cu" "F.Mask" "F.Paste")
			(net "GND")
			(options
				(clearance outline)
				(anchor circle)
			)
			(primitives
				(gr_poly
					(pts
						(arc
							(start -0.1778 0.5715)
							(mid -0.321484 0.511984)
							(end -0.381 0.3683)
						)
						(arc
							(start -0.381 -0.3683)
							(mid -0.321484 -0.511984)
							(end -0.1778 -0.5715)
						)
						(arc
							(start 0.1778 -0.5715)
							(mid 0.321484 -0.511984)
							(end 0.381 -0.3683)
						)
						(arc
							(start 0.381 0.3683)
							(mid 0.321484 0.511984)
							(end 0.1778 0.5715)
						)
					)
					(width 0)
					(fill yes)
				)
			)
		)
	)
	(footprint ""
		(layer "F.Cu")
		(at 222.87103 -357.961438)
		(property "Reference" "R425"
			(at 0 0 0)
			(layer "F.SilkS")
			(hide yes)
			(effects
				(font
					(size 1.27 1.27)
				)
			)
		)
		(property "Value" "1KR2F-3-GP"
			(at 0.064008 -3.993896 0)
			(unlocked yes)
			(layer "F.Fab")
			(hide yes)
			(effects
				(font
					(size 1.016 1.016)
					(thickness 0.1524)
				)
			)
		)
		(property "Device Type" "R402H16"
			(at 0.064008 -5.517896 0)
			(unlocked yes)
			(layer "F.Fab")
			(hide yes)
			(effects
				(font
					(size 1.016 1.016)
					(thickness 0.1524)
				)
			)
		)
		(duplicate_pad_numbers_are_jumpers no)
		(fp_line
			(start -0.508 -0.9398)
			(end -0.508 0.9398)
			(stroke
				(width 0.1524)
				(type default)
			)
			(layer "F.SilkS")
		)
		(fp_line
			(start 0.508 -0.9398)
			(end -0.508 -0.9398)
			(stroke
				(width 0.1524)
				(type default)
			)
			(layer "F.SilkS")
		)
		(fp_rect
			(start -0.508 0.9398)
			(end 0.508 -0.9398)
			(stroke
				(width 0)
				(type default)
			)
			(fill no)
			(layer "F.CrtYd")
		)
		(fp_rect
			(start -0.508 0.9398)
			(end 0.508 -0.9398)
			(stroke
				(width 0)
				(type default)
			)
			(fill no)
			(layer "F.Fab")
		)
		(pad "1" smd custom
			(at 0 -0.4445)
			(size 0.1397 0.1397)
			(layers "F.Cu" "F.Mask" "F.Paste")
			(net "P3V3_STBY_A")
			(options
				(clearance outline)
				(anchor circle)
			)
			(primitives
				(gr_poly
					(pts
						(arc
							(start -0.1778 -0.2794)
							(mid -0.249642 -0.249642)
							(end -0.2794 -0.1778)
						)
						(arc
							(start -0.2794 0.1778)
							(mid -0.249642 0.249642)
							(end -0.1778 0.2794)
						)
						(arc
							(start 0.1778 0.2794)
							(mid 0.249642 0.249642)
							(end 0.2794 0.1778)
						)
						(arc
							(start 0.2794 -0.1778)
							(mid 0.249642 -0.249642)
							(end 0.1778 -0.2794)
						)
					)
					(width 0)
					(fill yes)
				)
			)
		)
		(pad "2" smd custom
			(at 0 0.4445)
			(size 0.1397 0.1397)
			(layers "F.Cu" "F.Mask" "F.Paste")
			(net "I2C_CLIP_A_SDA")
			(options
				(clearance outline)
				(anchor circle)
			)
			(primitives
				(gr_poly
					(pts
						(arc
							(start -0.1778 -0.2794)
							(mid -0.249642 -0.249642)
							(end -0.2794 -0.1778)
						)
						(arc
							(start -0.2794 0.1778)
							(mid -0.249642 0.249642)
							(end -0.1778 0.2794)
						)
						(arc
							(start 0.1778 0.2794)
							(mid 0.249642 0.249642)
							(end 0.2794 0.1778)
						)
						(arc
							(start 0.2794 -0.1778)
							(mid 0.249642 -0.249642)
							(end 0.1778 -0.2794)
						)
					)
					(width 0)
					(fill yes)
				)
			)
		)
	)
	(footprint ""
		(layer "F.Cu")
		(at 402.553932 -130.400298 -90)
		(property "Reference" "R540"
			(at 0 0 270)
			(layer "F.SilkS")
			(hide yes)
			(effects
				(font
					(size 1.27 1.27)
				)
			)
		)
		(property "Value" "4K7R2J-2-GP"
			(at 0.064008 -3.993896 270)
			(unlocked yes)
			(layer "F.Fab")
			(hide yes)
			(effects
				(font
					(size 1.016 1.016)
					(thickness 0.1524)
				)
			)
		)
		(property "Device Type" "R402H16"
			(at 0.064008 -5.517896 270)
			(unlocked yes)
			(layer "F.Fab")
			(hide yes)
			(effects
				(font
					(size 1.016 1.016)
					(thickness 0.1524)
				)
			)
		)
		(duplicate_pad_numbers_are_jumpers no)
		(fp_line
			(start -0.508 -0.9398)
			(end -0.508 0.9398)
			(stroke
				(width 0.1524)
				(type default)
			)
			(layer "F.SilkS")
		)
		(fp_line
			(start 0.508 -0.9398)
			(end -0.508 -0.9398)
			(stroke
				(width 0.1524)
				(type default)
			)
			(layer "F.SilkS")
		)
		(fp_rect
			(start -0.508 0.9398)
			(end 0.508 -0.9398)
			(stroke
				(width 0)
				(type default)
			)
			(fill no)
			(layer "F.CrtYd")
		)
		(fp_rect
			(start -0.508 0.9398)
			(end 0.508 -0.9398)
			(stroke
				(width 0)
				(type default)
			)
			(fill no)
			(layer "F.Fab")
		)
		(pad "1" smd custom
			(at 0 -0.4445 270)
			(size 0.1397 0.1397)
			(layers "F.Cu" "F.Mask" "F.Paste")
			(net "DRIVE_A_21_ACT")
			(options
				(clearance outline)
				(anchor circle)
			)
			(primitives
				(gr_poly
					(pts
						(arc
							(start -0.1778 -0.2794)
							(mid -0.249642 -0.249642)
							(end -0.2794 -0.1778)
						)
						(arc
							(start -0.2794 0.1778)
							(mid -0.249642 0.249642)
							(end -0.1778 0.2794)
						)
						(arc
							(start 0.1778 0.2794)
							(mid 0.249642 0.249642)
							(end 0.2794 0.1778)
						)
						(arc
							(start 0.2794 -0.1778)
							(mid 0.249642 -0.249642)
							(end 0.1778 -0.2794)
						)
					)
					(width 0)
					(fill yes)
				)
			)
		)
		(pad "2" smd custom
			(at 0 0.4445 270)
			(size 0.1397 0.1397)
			(layers "F.Cu" "F.Mask" "F.Paste")
			(net "GND")
			(options
				(clearance outline)
				(anchor circle)
			)
			(primitives
				(gr_poly
					(pts
						(arc
							(start -0.1778 -0.2794)
							(mid -0.249642 -0.249642)
							(end -0.2794 -0.1778)
						)
						(arc
							(start -0.2794 0.1778)
							(mid -0.249642 0.249642)
							(end -0.1778 0.2794)
						)
						(arc
							(start 0.1778 0.2794)
							(mid 0.249642 0.249642)
							(end 0.2794 0.1778)
						)
						(arc
							(start 0.2794 -0.1778)
							(mid 0.249642 -0.249642)
							(end 0.1778 -0.2794)
						)
					)
					(width 0)
					(fill yes)
				)
			)
		)
	)
	(footprint ""
		(layer "F.Cu")
		(at 427.009052 -180.826918 180)
		(property "Reference" "C314"
			(at 0 0 180)
			(layer "F.SilkS")
			(hide yes)
			(effects
				(font
					(size 1.27 1.27)
				)
			)
		)
		(property "Value" "SC10U16V6KX-2GP"
			(at -0.0762 -5.1308 180)
			(unlocked yes)
			(layer "F.Fab")
			(hide yes)
			(effects
				(font
					(size 1.016 1.016)
					(thickness 0.1524)
				)
			)
		)
		(property "Device Type" "C1206H71"
			(at -0.127 -6.6548 180)
			(unlocked yes)
			(layer "F.Fab")
			(hide yes)
			(effects
				(font
					(size 1.016 1.016)
					(thickness 0.1524)
				)
			)
		)
		(duplicate_pad_numbers_are_jumpers no)
		(fp_line
			(start 1.016 2.2352)
			(end -1.016 2.2352)
			(stroke
				(width 0.1524)
				(type default)
			)
			(layer "F.SilkS")
		)
		(fp_line
			(start 1.016 0.8382)
			(end 1.016 2.2352)
			(stroke
				(width 0.1524)
				(type default)
			)
			(layer "F.SilkS")
		)
		(fp_line
			(start 1.016 -2.2352)
			(end 1.016 -0.8382)
			(stroke
				(width 0.1524)
				(type default)
			)
			(layer "F.SilkS")
		)
		(fp_line
			(start -1.016 2.2352)
			(end -1.016 0.8382)
			(stroke
				(width 0.1524)
				(type default)
			)
			(layer "F.SilkS")
		)
		(fp_line
			(start -1.016 -0.8382)
			(end -1.016 -2.2352)
			(stroke
				(width 0.1524)
				(type default)
			)
			(layer "F.SilkS")
		)
		(fp_line
			(start -1.016 -2.2352)
			(end 1.016 -2.2352)
			(stroke
				(width 0.1524)
				(type default)
			)
			(layer "F.SilkS")
		)
		(fp_rect
			(start -1.0922 2.3114)
			(end 1.0922 -2.3114)
			(stroke
				(width 0)
				(type default)
			)
			(fill no)
			(layer "F.CrtYd")
		)
		(fp_poly
			(pts
				(xy 1.0922 -2.3114) (xy 1.0922 2.3114) (xy -1.0922 2.3114) (xy -1.0922 -2.3114)
			)
			(stroke
				(width 0)
				(type default)
			)
			(fill no)
			(layer "F.Fab")
		)
		(pad "1" smd rect
			(at 0 -1.397 180)
			(size 1.651 1.27)
			(layers "F.Cu" "F.Mask" "F.Paste")
			(net "P5V_HDD21")
		)
		(pad "2" smd rect
			(at 0 1.397 180)
			(size 1.651 1.27)
			(layers "F.Cu" "F.Mask" "F.Paste")
			(net "GND")
		)
	)
	(footprint ""
		(layer "F.Cu")
		(at 48.424846 -46.649894 180)
		(property "Reference" "D25"
			(at 0 0 180)
			(layer "F.SilkS")
			(hide yes)
			(effects
				(font
					(size 1.27 1.27)
				)
			)
		)
		(property "Value" "RB551V30-GP"
			(at 0 -6.7818 180)
			(unlocked yes)
			(layer "F.Fab")
			(hide yes)
			(effects
				(font
					(size 1.016 1.016)
					(thickness 0.1524)
				)
			)
		)
		(property "Device Type" "SOD323AKH38"
			(at 0 -8.6868 180)
			(unlocked yes)
			(layer "F.Fab")
			(hide yes)
			(effects
				(font
					(size 1.016 1.016)
					(thickness 0.1524)
				)
			)
		)
		(duplicate_pad_numbers_are_jumpers no)
		(fp_line
			(start 0.889 2.159)
			(end -0.889 2.159)
			(stroke
				(width 0.1524)
				(type default)
			)
			(layer "F.SilkS")
		)
		(fp_line
			(start 0.889 -1.9304)
			(end 0.889 2.159)
			(stroke
				(width 0.1524)
				(type default)
			)
			(layer "F.SilkS")
		)
		(fp_line
			(start 0.762 2.0574)
			(end -0.762 2.0574)
			(stroke
				(width 0.508)
				(type default)
			)
			(layer "F.SilkS")
		)
		(fp_line
			(start -0.889 2.159)
			(end -0.889 -1.9304)
			(stroke
				(width 0.1524)
				(type default)
			)
			(layer "F.SilkS")
		)
		(fp_line
			(start -0.889 -1.9304)
			(end 0.889 -1.9304)
			(stroke
				(width 0.1524)
				(type default)
			)
			(layer "F.SilkS")
		)
		(fp_rect
			(start -1.016 2.3114)
			(end 1.016 -2.0066)
			(stroke
				(width 0)
				(type default)
			)
			(fill no)
			(layer "F.CrtYd")
		)
		(fp_poly
			(pts
				(xy -1.016 -2.0066) (xy 1.016 -2.0066) (xy 1.016 2.3114) (xy -1.016 2.3114)
			)
			(stroke
				(width 0)
				(type default)
			)
			(fill no)
			(layer "F.Fab")
		)
		(pad "A" smd rect
			(at 0 -1.143 180)
			(size 0.5588 1.016)
			(layers "F.Cu" "F.Mask" "F.Paste")
			(net "SW_HDD_R25")
		)
		(pad "K" smd rect
			(at 0 1.143 180)
			(size 0.5588 1.016)
			(layers "F.Cu" "F.Mask" "F.Paste")
			(net "SW_HDD_N25")
		)
	)
	(footprint ""
		(layer "F.Cu")
		(at 333.502 -188.954918 180)
		(property "Reference" "C280"
			(at 0 0 180)
			(layer "F.SilkS")
			(hide yes)
			(effects
				(font
					(size 1.27 1.27)
				)
			)
		)
		(property "Value" "SC4D7U25V5KX-1-GP"
			(at -0.0762 -6.1214 180)
			(unlocked yes)
			(layer "F.Fab")
			(hide yes)
			(effects
				(font
					(size 1.016 1.016)
					(thickness 0.1524)
				)
			)
		)
		(property "Device Type" "C805H58"
			(at -0.0762 -8.1534 180)
			(unlocked yes)
			(layer "F.Fab")
			(hide yes)
			(effects
				(font
					(size 1.016 1.016)
					(thickness 0.1524)
				)
			)
		)
		(duplicate_pad_numbers_are_jumpers no)
		(fp_line
			(start 0.635 0)
			(end -0.635 0)
			(stroke
				(width 0.508)
				(type default)
			)
			(layer "F.SilkS")
		)
		(fp_rect
			(start -0.9652 1.778)
			(end 0.9652 -1.778)
			(stroke
				(width 0)
				(type default)
			)
			(fill no)
			(layer "F.CrtYd")
		)
		(fp_poly
			(pts
				(xy -0.9652 -1.778) (xy 0.9652 -1.778) (xy 0.9652 1.778) (xy -0.9652 1.778)
			)
			(stroke
				(width 0)
				(type default)
			)
			(fill no)
			(layer "F.Fab")
		)
		(pad "1" smd rect
			(at 0 -0.9652 180)
			(size 1.397 1.143)
			(layers "F.Cu" "F.Mask" "F.Paste")
			(net "P12V_HDD18")
		)
		(pad "2" smd rect
			(at 0 0.9652 180)
			(size 1.397 1.143)
			(layers "F.Cu" "F.Mask" "F.Paste")
			(net "GND")
		)
	)
	(footprint ""
		(layer "F.Cu")
		(at 69.619622 -185.06059)
		(property "Reference" "Q265"
			(at 0 0 0)
			(layer "F.SilkS")
			(hide yes)
			(effects
				(font
					(size 1.27 1.27)
				)
			)
		)
		(property "Value" "SSM3K324R-GP"
			(at 0.127 -8.9662 0)
			(unlocked yes)
			(layer "F.Fab")
			(hide yes)
			(effects
				(font
					(size 1.016 1.016)
					(thickness 0.1524)
				)
			)
		)
		(property "Device Type" "SOT23DGS2D4H35"
			(at 0.127 -10.4902 0)
			(unlocked yes)
			(layer "F.Fab")
			(hide yes)
			(effects
				(font
					(size 1.016 1.016)
					(thickness 0.1524)
				)
			)
		)
		(duplicate_pad_numbers_are_jumpers no)
		(fp_line
			(start -1.651 -1.778)
			(end -1.651 1.778)
			(stroke
				(width 0.1524)
				(type default)
			)
			(layer "F.SilkS")
		)
		(fp_line
			(start -1.651 1.778)
			(end 1.651 1.778)
			(stroke
				(width 0.1524)
				(type default)
			)
			(layer "F.SilkS")
		)
		(fp_line
			(start 1.651 -1.778)
			(end -1.651 -1.778)
			(stroke
				(width 0.1524)
				(type default)
			)
			(layer "F.SilkS")
		)
		(fp_line
			(start 1.651 1.778)
			(end 1.651 -1.778)
			(stroke
				(width 0.1524)
				(type default)
			)
			(layer "F.SilkS")
		)
		(fp_poly
			(pts
				(xy -1.778 1.8796) (xy -1.778 -1.8796) (xy 1.778 -1.8796) (xy 1.778 1.8796)
			)
			(stroke
				(width 0)
				(type default)
			)
			(fill no)
			(layer "F.CrtYd")
		)
		(fp_poly
			(pts
				(xy -1.778 1.8796) (xy -1.778 -1.8796) (xy 1.778 -1.8796) (xy 1.778 1.8796)
			)
			(stroke
				(width 0)
				(type default)
			)
			(fill no)
			(layer "F.Fab")
		)
		(pad "D" smd custom
			(at 0 -0.9525)
			(size 0.1905 0.1905)
			(layers "F.Cu" "F.Mask" "F.Paste")
			(net "DRV_ACT_2_N")
			(options
				(clearance outline)
				(anchor circle)
			)
			(primitives
				(gr_poly
					(pts
						(arc
							(start -0.1778 0.5715)
							(mid -0.321484 0.511984)
							(end -0.381 0.3683)
						)
						(arc
							(start -0.381 -0.3683)
							(mid -0.321484 -0.511984)
							(end -0.1778 -0.5715)
						)
						(arc
							(start 0.1778 -0.5715)
							(mid 0.321484 -0.511984)
							(end 0.381 -0.3683)
						)
						(arc
							(start 0.381 0.3683)
							(mid 0.321484 0.511984)
							(end 0.1778 0.5715)
						)
					)
					(width 0)
					(fill yes)
				)
			)
		)
		(pad "G" smd custom
			(at -0.98425 0.9525)
			(size 0.1905 0.1905)
			(layers "F.Cu" "F.Mask" "F.Paste")
			(net "DRIVE_A_2_ACT")
			(options
				(clearance outline)
				(anchor circle)
			)
			(primitives
				(gr_poly
					(pts
						(arc
							(start -0.1778 0.5715)
							(mid -0.321484 0.511984)
							(end -0.381 0.3683)
						)
						(arc
							(start -0.381 -0.3683)
							(mid -0.321484 -0.511984)
							(end -0.1778 -0.5715)
						)
						(arc
							(start 0.1778 -0.5715)
							(mid 0.321484 -0.511984)
							(end 0.381 -0.3683)
						)
						(arc
							(start 0.381 0.3683)
							(mid 0.321484 0.511984)
							(end 0.1778 0.5715)
						)
					)
					(width 0)
					(fill yes)
				)
			)
		)
		(pad "S" smd custom
			(at 0.98425 0.9525)
			(size 0.1905 0.1905)
			(layers "F.Cu" "F.Mask" "F.Paste")
			(net "GND")
			(options
				(clearance outline)
				(anchor circle)
			)
			(primitives
				(gr_poly
					(pts
						(arc
							(start -0.1778 0.5715)
							(mid -0.321484 0.511984)
							(end -0.381 0.3683)
						)
						(arc
							(start -0.381 -0.3683)
							(mid -0.321484 -0.511984)
							(end -0.1778 -0.5715)
						)
						(arc
							(start 0.1778 -0.5715)
							(mid 0.321484 -0.511984)
							(end 0.381 -0.3683)
						)
						(arc
							(start 0.381 0.3683)
							(mid 0.321484 0.511984)
							(end 0.1778 0.5715)
						)
					)
					(width 0)
					(fill yes)
				)
			)
		)
	)
)
